# S9S_MB_2U (Grand Teton) — schematic netlist excerpt (pin names and nets, part order shuffled) for the footprints in the layout excerpt that follows; sources: Cadence DE-HDL packaged netlist, KiCad conversion of 03242023_DA0F0TMBIJ0_F0T_Motherboard_J_brd_V01_OCP.brd

C1945  Q_CAP  0.1UF 25V 10% X7R  pkg 0402  page 217 : A = P3V3_AUX_FPGA_VCCIO0 ; B = GND

X39  TP_TDR_4P_FTS  TP_TDR_4P_DIP EMPTY  pkg TH  page 310
  S1  = UNNAMED_310_TPTDR4PFTS_I20_S2
  P1  = T1_GND
  P2  = T1_GND
  S2  = UNNAMED_310_TPTDR4PFTS_I20_S1

(kicad_pcb
	(version 20260206)
	(generator "pcbnew")
	(generator_version "10.0")
	(general
		(thickness 1.6)
		(legacy_teardrops no)
	)
	(paper "A4")
	(title_block
		(title "03242023_DA0F0TMBIJ0_F0T_Motherboard_J_brd_V01_OCP.brd")
		(comment 1 "Grand Teton / footprints 5553-5554 of 6105")
	)
	(layers
		(0 "F.Cu" signal "TOP")
		(4 "In1.Cu" signal "GND")
		(6 "In2.Cu" signal "IN1")
		(8 "In3.Cu" signal "GND1")
		(10 "In4.Cu" signal "IN2")
		(12 "In5.Cu" signal "GND2")
		(14 "In6.Cu" signal "IN3")
		(16 "In7.Cu" signal "GND3")
		(18 "In8.Cu" signal "VCC")
		(20 "In9.Cu" signal "VCC1")
		(22 "In10.Cu" signal "GND4")
		(24 "In11.Cu" signal "IN4")
		(26 "In12.Cu" signal "GND5")
		(28 "In13.Cu" signal "IN5")
		(30 "In14.Cu" signal "GND6")
		(32 "In15.Cu" signal "IN6")
		(34 "In16.Cu" signal "GND7")
		(2 "B.Cu" signal "BOTTOM")
		(9 "F.Adhes" user "F.Adhesive")
		(11 "B.Adhes" user "B.Adhesive")
		(13 "F.Paste" user "Package Geometry/Pastemask Top")
		(15 "B.Paste" user "Package Geometry/Pastemask Bottom")
		(5 "F.SilkS" user "Ref Des/Silkscreen Top")
		(7 "B.SilkS" user "Ref Des/Silkscreen Bottom")
		(1 "F.Mask" user "Board Geometry/Soldermask Top")
		(3 "B.Mask" user "Board Geometry/Soldermask Bottom")
		(17 "Dwgs.User" user "User.Drawings")
		(19 "Cmts.User" user "User.Comments")
		(21 "Eco1.User" user "User.Eco1")
		(23 "Eco2.User" user "User.Eco2")
		(25 "Edge.Cuts" user "Board Geometry/Outline")
		(27 "Margin" user)
		(31 "F.CrtYd" user "Package Geometry/Place Bound Top")
		(29 "B.CrtYd" user "Package Geometry/Place Bound Bottom")
		(35 "F.Fab" user "Ref Des/Assembly Top")
		(33 "B.Fab" user "Ref Des/Assembly Bottom")
	)
	(footprint ""
		(layer "B.Cu")
		(at 168.83888 -103.723948)
		(property "Reference" "C1945"
			(at 0 0 0)
			(layer "B.SilkS")
			(hide yes)
			(effects
				(font
					(size 1.27 1.27)
				)
				(justify mirror)
			)
		)
		(property "Value" ""
			(at 0 0 0)
			(layer "B.Fab")
			(effects
				(font
					(size 1.27 1.27)
				)
				(justify mirror)
			)
		)
		(duplicate_pad_numbers_are_jumpers no)
		(fp_line
			(start -0.7874 -0.4064)
			(end -0.7874 0.4064)
			(stroke
				(width 0.1524)
				(type default)
			)
			(layer "B.SilkS")
		)
		(fp_line
			(start -0.7874 0.4064)
			(end 0.7874 0.4064)
			(stroke
				(width 0.1524)
				(type default)
			)
			(layer "B.SilkS")
		)
		(fp_line
			(start 0.7874 -0.4064)
			(end -0.7874 -0.4064)
			(stroke
				(width 0.1524)
				(type default)
			)
			(layer "B.SilkS")
		)
		(fp_line
			(start 0.7874 0.4064)
			(end 0.7874 -0.4064)
			(stroke
				(width 0.1524)
				(type default)
			)
			(layer "B.SilkS")
		)
		(fp_line
			(start -0.67945 -0.3048)
			(end -0.67945 0.3048)
			(stroke
				(width 0.1)
				(type default)
			)
			(layer "B.Fab")
		)
		(fp_line
			(start -0.67945 0.3048)
			(end -0.120396 0.3048)
			(stroke
				(width 0.1)
				(type default)
			)
			(layer "B.Fab")
		)
		(fp_line
			(start -0.12065 -0.3048)
			(end -0.67945 -0.3048)
			(stroke
				(width 0.1)
				(type default)
			)
			(layer "B.Fab")
		)
		(fp_line
			(start -0.12065 -0.2794)
			(end -0.12065 -0.3048)
			(stroke
				(width 0.1)
				(type default)
			)
			(layer "B.Fab")
		)
		(fp_line
			(start -0.120396 0.2794)
			(end 0.12065 0.2794)
			(stroke
				(width 0.1)
				(type default)
			)
			(layer "B.Fab")
		)
		(fp_line
			(start -0.120396 0.3048)
			(end -0.120396 0.2794)
			(stroke
				(width 0.1)
				(type default)
			)
			(layer "B.Fab")
		)
		(fp_line
			(start 0.12065 -0.305054)
			(end 0.12065 -0.2794)
			(stroke
				(width 0.1)
				(type default)
			)
			(layer "B.Fab")
		)
		(fp_line
			(start 0.12065 -0.2794)
			(end -0.12065 -0.2794)
			(stroke
				(width 0.1)
				(type default)
			)
			(layer "B.Fab")
		)
		(fp_line
			(start 0.12065 0.2794)
			(end 0.12065 0.3048)
			(stroke
				(width 0.1)
				(type default)
			)
			(layer "B.Fab")
		)
		(fp_line
			(start 0.12065 0.3048)
			(end 0.67945 0.3048)
			(stroke
				(width 0.1)
				(type default)
			)
			(layer "B.Fab")
		)
		(fp_line
			(start 0.67945 -0.305054)
			(end 0.12065 -0.305054)
			(stroke
				(width 0.1)
				(type default)
			)
			(layer "B.Fab")
		)
		(fp_line
			(start 0.67945 0.3048)
			(end 0.67945 -0.305054)
			(stroke
				(width 0.1)
				(type default)
			)
			(layer "B.Fab")
		)
		(pad "1" smd circle
			(at 0.40005 0 180)
			(size 0 0)
			(layers "B.Cu" "B.Mask" "B.Paste")
			(net "P3V3_AUX_FPGA_VCCIO0")
		)
		(pad "2" smd circle
			(at -0.40005 0 180)
			(size 0 0)
			(layers "B.Cu" "B.Mask" "B.Paste")
			(net "GND")
		)
	)
	(footprint ""
		(layer "B.Cu")
		(at 479.84537 -116.560092 -90)
		(property "Reference" "X39"
			(at -0.279908 -2.21996 270)
			(unlocked yes)
			(layer "B.SilkS")
			(effects
				(font
					(size 0.7874 0.5842)
					(thickness 0.1524)
				)
				(justify left mirror)
			)
		)
		(property "Value" ""
			(at 0 0 90)
			(layer "B.Fab")
			(effects
				(font
					(size 1.27 1.27)
				)
				(justify mirror)
			)
		)
		(property "Device Type" "TP_TDR_4P_FTS_TH-TP_TDR_4P_DIPA"
			(at -1.30175 1.27 180)
			(unlocked yes)
			(layer "B.Fab")
			(hide yes)
			(effects
				(font
					(size 0.635 0.4064)
					(thickness 0.1524)
				)
				(justify mirror)
			)
		)
		(property "User Part Number" "N_A"
			(at -1.30175 1.27 180)
			(unlocked yes)
			(layer "Cmts.User")
			(hide yes)
			(effects
				(font
					(size 0.635 0.4064)
					(thickness 0.1524)
				)
				(justify mirror)
			)
		)
		(duplicate_pad_numbers_are_jumpers no)
		(fp_line
			(start -2.54 3.81)
			(end -2.54 3.6703)
			(stroke
				(width 0.1524)
				(type default)
			)
			(layer "B.SilkS")
		)
		(fp_line
			(start 0 3.81)
			(end -2.54 3.81)
			(stroke
				(width 0.1524)
				(type default)
			)
			(layer "B.SilkS")
		)
		(fp_line
			(start 0 3.175)
			(end 0 3.81)
			(stroke
				(width 0.1524)
				(type default)
			)
			(layer "B.SilkS")
		)
		(fp_line
			(start -2.54 1.4097)
			(end -2.54 1.1303)
			(stroke
				(width 0.1524)
				(type default)
			)
			(layer "B.SilkS")
		)
		(fp_line
			(start 0 0.635)
			(end 0 1.905)
			(stroke
				(width 0.1524)
				(type default)
			)
			(layer "B.SilkS")
		)
		(fp_line
			(start -2.54 -1.1303)
			(end -2.54 -1.27)
			(stroke
				(width 0.1524)
				(type default)
			)
			(layer "B.SilkS")
		)
		(fp_line
			(start -2.54 -1.27)
			(end 0 -1.27)
			(stroke
				(width 0.1524)
				(type default)
			)
			(layer "B.SilkS")
		)
		(fp_line
			(start 0 -1.27)
			(end 0 -0.635)
			(stroke
				(width 0.1524)
				(type default)
			)
			(layer "B.SilkS")
		)
		(fp_poly
			(pts
				(xy 0.761746 0) (xy 2.285746 -0.762) (xy 2.285746 0.762)
			)
			(stroke
				(width 0)
				(type default)
			)
			(fill yes)
			(layer "B.SilkS")
		)
		(fp_line
			(start -2.54 3.81)
			(end -2.54 -1.27)
			(stroke
				(width 0.1)
				(type default)
			)
			(layer "B.Fab")
		)
		(fp_line
			(start 0 3.81)
			(end -2.54 3.81)
			(stroke
				(width 0.1)
				(type default)
			)
			(layer "B.Fab")
		)
		(fp_line
			(start -2.54 -1.27)
			(end 0 -1.27)
			(stroke
				(width 0.1)
				(type default)
			)
			(layer "B.Fab")
		)
		(fp_line
			(start 0 -1.27)
			(end 0 3.81)
			(stroke
				(width 0.1)
				(type default)
			)
			(layer "B.Fab")
		)
		(fp_poly
			(pts
				(xy 0.761746 0) (xy 2.285746 -0.762) (xy 2.285746 0.762)
			)
			(stroke
				(width 0)
				(type default)
			)
			(fill yes)
			(layer "B.Fab")
		)
		(pad "1" thru_hole circle
			(at 0 0 90)
			(size 1.0033 1.0033)
			(drill 0.249936)
			(layers "*.Cu" "*.Mask")
			(remove_unused_layers no)
			(net "TDR_DIFF_85_NECK_IN6_DP")
			(clearance 0.10795)
			(padstack
				(mode front_inner_back)
				(layer "Inner"
					(shape circle)
					(size 0.8001 0.8001)
					(clearance 0.1524)
				)
				(layer "B.Cu"
					(shape circle)
					(size 1.0033 1.0033)
					(thermal_gap 0.10795)
					(clearance 0.10795)
				)
			)
		)
		(pad "2" thru_hole circle
			(at -2.54 0 90)
			(size 1.9939 1.9939)
			(drill 0.249936)
			(layers "*.Cu" "*.Mask")
			(remove_unused_layers no)
			(net "T1_GND")
			(clearance 0.10795)
			(padstack
				(mode front_inner_back)
				(layer "Inner"
					(shape circle)
					(size 0.8001 0.8001)
					(clearance 0.1524)
				)
				(layer "B.Cu"
					(shape circle)
					(size 1.9939 1.9939)
					(thermal_gap 0.10795)
					(clearance 0.10795)
				)
			)
		)
		(pad "3" thru_hole circle
			(at -2.54 2.54 90)
			(size 1.9939 1.9939)
			(drill 0.249936)
			(layers "*.Cu" "*.Mask")
			(remove_unused_layers no)
			(net "T1_GND")
			(clearance 0.10795)
			(padstack
				(mode front_inner_back)
				(layer "Inner"
					(shape circle)
					(size 0.8001 0.8001)
					(clearance 0.1524)
				)
				(layer "B.Cu"
					(shape circle)
					(size 1.9939 1.9939)
					(thermal_gap 0.10795)
					(clearance 0.10795)
				)
			)
		)
		(pad "4" thru_hole circle
			(at 0 2.54 90)
			(size 1.0033 1.0033)
			(drill 0.249936)
			(layers "*.Cu" "*.Mask")
			(remove_unused_layers no)
			(net "TDR_DIFF_85_NECK_IN6_DN")
			(clearance 0.10795)
			(padstack
				(mode front_inner_back)
				(layer "Inner"
					(shape circle)
					(size 0.8001 0.8001)
					(clearance 0.1524)
				)
				(layer "B.Cu"
					(shape circle)
					(size 1.0033 1.0033)
					(thermal_gap 0.10795)
					(clearance 0.10795)
				)
			)
		)
	)
)
